(kicad_pcb
	(version 20260206)
	(generator "pcbnew")
	(generator_version "10.0")
	(general
		(thickness 1.6)
		(legacy_teardrops no)
	)
	(paper "A4")
	(title_block
		(title "01162023_DA0F0TEBIF0_F0T_Expander_BD_F_brd_V02_OCP.brd")
		(comment 1 "Grand Teton / footprints 80-86 of 9728")
	)
	(layers
		(0 "F.Cu" signal "TOP")
		(4 "In1.Cu" signal "GND")
		(6 "In2.Cu" signal "VCC")
		(8 "In3.Cu" signal "VCC1")
		(10 "In4.Cu" signal "GND1")
		(12 "In5.Cu" signal "IN1")
		(14 "In6.Cu" signal "GND2")
		(16 "In7.Cu" signal "IN2")
		(18 "In8.Cu" signal "GND3")
		(20 "In9.Cu" signal "IN3")
		(22 "In10.Cu" signal "GND4")
		(24 "In11.Cu" signal "IN4")
		(26 "In12.Cu" signal "GND5")
		(28 "In13.Cu" signal "IN5")
		(30 "In14.Cu" signal "GND6")
		(32 "In15.Cu" signal "IN6")
		(34 "In16.Cu" signal "GND7")
		(2 "B.Cu" signal "BOTTOM")
		(9 "F.Adhes" user "F.Adhesive")
		(11 "B.Adhes" user "B.Adhesive")
		(13 "F.Paste" user "Package Geometry/Pastemask Top")
		(15 "B.Paste" user "Package Geometry/Pastemask Bottom")
		(5 "F.SilkS" user "Ref Des/Silkscreen Top")
		(7 "B.SilkS" user "Ref Des/Silkscreen Bottom")
		(1 "F.Mask" user "Board Geometry/Soldermask Top")
		(3 "B.Mask" user "Board Geometry/Soldermask Bottom")
		(17 "Dwgs.User" user "User.Drawings")
		(19 "Cmts.User" user "User.Comments")
		(21 "Eco1.User" user "User.Eco1")
		(23 "Eco2.User" user "User.Eco2")
		(25 "Edge.Cuts" user "Board Geometry/Outline")
		(27 "Margin" user)
		(31 "F.CrtYd" user "Package Geometry/Place Bound Top")
		(29 "B.CrtYd" user "Package Geometry/Place Bound Bottom")
		(35 "F.Fab" user "Ref Des/Assembly Top")
		(33 "B.Fab" user "Ref Des/Assembly Bottom")
	)
	(footprint ""
		(layer "F.Cu")
		(at 98.975672 -123.795028)
		(property "Reference" "C2879"
			(at 0 0 0)
			(layer "F.SilkS")
			(hide yes)
			(effects
				(font
					(size 1.27 1.27)
				)
			)
		)
		(property "Value" ""
			(at 0 0 0)
			(layer "F.Fab")
			(effects
				(font
					(size 1.27 1.27)
				)
			)
		)
		(duplicate_pad_numbers_are_jumpers no)
		(fp_line
			(start -0.7874 -0.4064)
			(end 0.7874 -0.4064)
			(stroke
				(width 0.1524)
				(type default)
			)
			(layer "F.SilkS")
		)
		(fp_line
			(start -0.7874 0.4064)
			(end -0.7874 -0.4064)
			(stroke
				(width 0.1524)
				(type default)
			)
			(layer "F.SilkS")
		)
		(fp_line
			(start 0.7874 -0.4064)
			(end 0.7874 0.4064)
			(stroke
				(width 0.1524)
				(type default)
			)
			(layer "F.SilkS")
		)
		(fp_line
			(start 0.7874 0.4064)
			(end -0.7874 0.4064)
			(stroke
				(width 0.1524)
				(type default)
			)
			(layer "F.SilkS")
		)
		(fp_line
			(start -0.67945 -0.305054)
			(end -0.12065 -0.305054)
			(stroke
				(width 0.1)
				(type default)
			)
			(layer "F.Fab")
		)
		(fp_line
			(start -0.67945 0.3048)
			(end -0.67945 -0.305054)
			(stroke
				(width 0.1)
				(type default)
			)
			(layer "F.Fab")
		)
		(fp_line
			(start -0.12065 -0.305054)
			(end -0.12065 -0.2794)
			(stroke
				(width 0.1)
				(type default)
			)
			(layer "F.Fab")
		)
		(fp_line
			(start -0.12065 -0.2794)
			(end 0.12065 -0.2794)
			(stroke
				(width 0.1)
				(type default)
			)
			(layer "F.Fab")
		)
		(fp_line
			(start -0.12065 0.2794)
			(end -0.12065 0.3048)
			(stroke
				(width 0.1)
				(type default)
			)
			(layer "F.Fab")
		)
		(fp_line
			(start -0.12065 0.3048)
			(end -0.67945 0.3048)
			(stroke
				(width 0.1)
				(type default)
			)
			(layer "F.Fab")
		)
		(fp_line
			(start 0.120396 0.2794)
			(end -0.12065 0.2794)
			(stroke
				(width 0.1)
				(type default)
			)
			(layer "F.Fab")
		)
		(fp_line
			(start 0.120396 0.3048)
			(end 0.120396 0.2794)
			(stroke
				(width 0.1)
				(type default)
			)
			(layer "F.Fab")
		)
		(fp_line
			(start 0.12065 -0.3048)
			(end 0.67945 -0.3048)
			(stroke
				(width 0.1)
				(type default)
			)
			(layer "F.Fab")
		)
		(fp_line
			(start 0.12065 -0.2794)
			(end 0.12065 -0.3048)
			(stroke
				(width 0.1)
				(type default)
			)
			(layer "F.Fab")
		)
		(fp_line
			(start 0.67945 -0.3048)
			(end 0.67945 0.3048)
			(stroke
				(width 0.1)
				(type default)
			)
			(layer "F.Fab")
		)
		(fp_line
			(start 0.67945 0.3048)
			(end 0.120396 0.3048)
			(stroke
				(width 0.1)
				(type default)
			)
			(layer "F.Fab")
		)
		(pad "1" smd circle
			(at -0.40005 0)
			(size 0 0)
			(layers "F.Cu" "F.Mask" "F.Paste")
			(net "HP_NIC1_EN")
		)
		(pad "2" smd circle
			(at 0.40005 0)
			(size 0 0)
			(layers "F.Cu" "F.Mask" "F.Paste")
			(net "GND")
		)
	)
	(footprint ""
		(layer "F.Cu")
		(at 123.203462 -59.571636 90)
		(property "Reference" "PR258"
			(at 0 0 90)
			(layer "F.SilkS")
			(hide yes)
			(effects
				(font
					(size 1.27 1.27)
				)
			)
		)
		(property "Value" ""
			(at 0 0 90)
			(layer "F.Fab")
			(effects
				(font
					(size 1.27 1.27)
				)
			)
		)
		(duplicate_pad_numbers_are_jumpers no)
		(fp_line
			(start 0.7874 -0.4064)
			(end 0.7874 0.4064)
			(stroke
				(width 0.1524)
				(type default)
			)
			(layer "F.SilkS")
		)
		(fp_line
			(start -0.7874 -0.4064)
			(end 0.7874 -0.4064)
			(stroke
				(width 0.1524)
				(type default)
			)
			(layer "F.SilkS")
		)
		(fp_line
			(start 0.7874 0.4064)
			(end -0.7874 0.4064)
			(stroke
				(width 0.1524)
				(type default)
			)
			(layer "F.SilkS")
		)
		(fp_line
			(start -0.7874 0.4064)
			(end -0.7874 -0.4064)
			(stroke
				(width 0.1524)
				(type default)
			)
			(layer "F.SilkS")
		)
		(fp_line
			(start -0.12065 -0.305054)
			(end -0.12065 -0.2794)
			(stroke
				(width 0.1)
				(type default)
			)
			(layer "F.Fab")
		)
		(fp_line
			(start -0.67945 -0.305054)
			(end -0.12065 -0.305054)
			(stroke
				(width 0.1)
				(type default)
			)
			(layer "F.Fab")
		)
		(fp_line
			(start 0.67945 -0.3048)
			(end 0.67945 0.3048)
			(stroke
				(width 0.1)
				(type default)
			)
			(layer "F.Fab")
		)
		(fp_line
			(start 0.12065 -0.3048)
			(end 0.67945 -0.3048)
			(stroke
				(width 0.1)
				(type default)
			)
			(layer "F.Fab")
		)
		(fp_line
			(start 0.12065 -0.2794)
			(end 0.12065 -0.3048)
			(stroke
				(width 0.1)
				(type default)
			)
			(layer "F.Fab")
		)
		(fp_line
			(start -0.12065 -0.2794)
			(end 0.12065 -0.2794)
			(stroke
				(width 0.1)
				(type default)
			)
			(layer "F.Fab")
		)
		(fp_line
			(start 0.120396 0.2794)
			(end -0.12065 0.2794)
			(stroke
				(width 0.1)
				(type default)
			)
			(layer "F.Fab")
		)
		(fp_line
			(start -0.12065 0.2794)
			(end -0.12065 0.3048)
			(stroke
				(width 0.1)
				(type default)
			)
			(layer "F.Fab")
		)
		(fp_line
			(start 0.67945 0.3048)
			(end 0.120396 0.3048)
			(stroke
				(width 0.1)
				(type default)
			)
			(layer "F.Fab")
		)
		(fp_line
			(start 0.120396 0.3048)
			(end 0.120396 0.2794)
			(stroke
				(width 0.1)
				(type default)
			)
			(layer "F.Fab")
		)
		(fp_line
			(start -0.12065 0.3048)
			(end -0.67945 0.3048)
			(stroke
				(width 0.1)
				(type default)
			)
			(layer "F.Fab")
		)
		(fp_line
			(start -0.67945 0.3048)
			(end -0.67945 -0.305054)
			(stroke
				(width 0.1)
				(type default)
			)
			(layer "F.Fab")
		)
		(pad "1" smd circle
			(at -0.40005 0 90)
			(size 0 0)
			(layers "F.Cu" "F.Mask" "F.Paste")
			(net "P3V3_SSD4_OCP")
		)
		(pad "2" smd circle
			(at 0.40005 0 90)
			(size 0 0)
			(layers "F.Cu" "F.Mask" "F.Paste")
			(net "GND")
		)
	)
	(footprint ""
		(layer "F.Cu")
		(at 329.438 -84.709 180)
		(property "Reference" "R1471"
			(at 0 0 180)
			(layer "F.SilkS")
			(hide yes)
			(effects
				(font
					(size 1.27 1.27)
				)
			)
		)
		(property "Value" ""
			(at 0 0 180)
			(layer "F.Fab")
			(effects
				(font
					(size 1.27 1.27)
				)
			)
		)
		(duplicate_pad_numbers_are_jumpers no)
		(fp_line
			(start 0.7874 0.4064)
			(end -0.7874 0.4064)
			(stroke
				(width 0.1524)
				(type default)
			)
			(layer "F.SilkS")
		)
		(fp_line
			(start 0.7874 -0.4064)
			(end 0.7874 0.4064)
			(stroke
				(width 0.1524)
				(type default)
			)
			(layer "F.SilkS")
		)
		(fp_line
			(start -0.7874 0.4064)
			(end -0.7874 -0.4064)
			(stroke
				(width 0.1524)
				(type default)
			)
			(layer "F.SilkS")
		)
		(fp_line
			(start -0.7874 -0.4064)
			(end 0.7874 -0.4064)
			(stroke
				(width 0.1524)
				(type default)
			)
			(layer "F.SilkS")
		)
		(fp_line
			(start 0.67945 0.3048)
			(end 0.120396 0.3048)
			(stroke
				(width 0.1)
				(type default)
			)
			(layer "F.Fab")
		)
		(fp_line
			(start 0.67945 -0.3048)
			(end 0.67945 0.3048)
			(stroke
				(width 0.1)
				(type default)
			)
			(layer "F.Fab")
		)
		(fp_line
			(start 0.12065 -0.2794)
			(end 0.12065 -0.3048)
			(stroke
				(width 0.1)
				(type default)
			)
			(layer "F.Fab")
		)
		(fp_line
			(start 0.12065 -0.3048)
			(end 0.67945 -0.3048)
			(stroke
				(width 0.1)
				(type default)
			)
			(layer "F.Fab")
		)
		(fp_line
			(start 0.120396 0.3048)
			(end 0.120396 0.2794)
			(stroke
				(width 0.1)
				(type default)
			)
			(layer "F.Fab")
		)
		(fp_line
			(start 0.120396 0.2794)
			(end -0.12065 0.2794)
			(stroke
				(width 0.1)
				(type default)
			)
			(layer "F.Fab")
		)
		(fp_line
			(start -0.12065 0.3048)
			(end -0.67945 0.3048)
			(stroke
				(width 0.1)
				(type default)
			)
			(layer "F.Fab")
		)
		(fp_line
			(start -0.12065 0.2794)
			(end -0.12065 0.3048)
			(stroke
				(width 0.1)
				(type default)
			)
			(layer "F.Fab")
		)
		(fp_line
			(start -0.12065 -0.2794)
			(end 0.12065 -0.2794)
			(stroke
				(width 0.1)
				(type default)
			)
			(layer "F.Fab")
		)
		(fp_line
			(start -0.12065 -0.305054)
			(end -0.12065 -0.2794)
			(stroke
				(width 0.1)
				(type default)
			)
			(layer "F.Fab")
		)
		(fp_line
			(start -0.67945 0.3048)
			(end -0.67945 -0.305054)
			(stroke
				(width 0.1)
				(type default)
			)
			(layer "F.Fab")
		)
		(fp_line
			(start -0.67945 -0.305054)
			(end -0.12065 -0.305054)
			(stroke
				(width 0.1)
				(type default)
			)
			(layer "F.Fab")
		)
		(pad "1" smd circle
			(at -0.40005 0 180)
			(size 0 0)
			(layers "F.Cu" "F.Mask" "F.Paste")
			(net "SMB_BMC_9ZXL0851_8_15_SDA")
		)
		(pad "2" smd circle
			(at 0.40005 0 180)
			(size 0 0)
			(layers "F.Cu" "F.Mask" "F.Paste")
			(net "SMB_ISO_CB_SDA")
		)
	)
	(footprint ""
		(layer "F.Cu")
		(at 481.686362 -554.994826 90)
		(property "Reference" "HS_BP3"
			(at -0.5842 -1.31953 90)
			(unlocked yes)
			(layer "B.SilkS")
			(effects
				(font
					(size 0.7874 0.5842)
					(thickness 0.1524)
				)
				(justify left mirror)
			)
		)
		(property "Value" ""
			(at 0 0 90)
			(layer "F.Fab")
			(effects
				(font
					(size 1.27 1.27)
				)
			)
		)
		(duplicate_pad_numbers_are_jumpers no)
		(pad "1" thru_hole circle
			(at 0 0 90)
			(size 0.4572 0.4572)
			(drill 0.2032)
			(layers "*.Cu" "*.Mask")
			(remove_unused_layers no)
			(net "Net_9199")
			(clearance 0.127)
			(thermal_gap 0.127)
			(padstack
				(mode front_inner_back)
				(layer "Inner"
					(shape circle)
					(size 0.4572 0.4572)
					(clearance 0.127)
				)
				(layer "B.Cu"
					(shape circle)
					(size 0.508 0.508)
					(clearance 0.1016)
				)
			)
		)
	)
	(footprint ""
		(layer "F.Cu")
		(at 95.177356 -201.109326 -90)
		(property "Reference" "R6621"
			(at 0 0 270)
			(layer "F.SilkS")
			(hide yes)
			(effects
				(font
					(size 1.27 1.27)
				)
			)
		)
		(property "Value" ""
			(at 0 0 270)
			(layer "F.Fab")
			(effects
				(font
					(size 1.27 1.27)
				)
			)
		)
		(duplicate_pad_numbers_are_jumpers no)
		(fp_line
			(start -0.7874 0.4064)
			(end -0.7874 -0.4064)
			(stroke
				(width 0.1524)
				(type default)
			)
			(layer "F.SilkS")
		)
		(fp_line
			(start 0.7874 0.4064)
			(end -0.7874 0.4064)
			(stroke
				(width 0.1524)
				(type default)
			)
			(layer "F.SilkS")
		)
		(fp_line
			(start -0.7874 -0.4064)
			(end 0.7874 -0.4064)
			(stroke
				(width 0.1524)
				(type default)
			)
			(layer "F.SilkS")
		)
		(fp_line
			(start 0.7874 -0.4064)
			(end 0.7874 0.4064)
			(stroke
				(width 0.1524)
				(type default)
			)
			(layer "F.SilkS")
		)
		(fp_line
			(start -0.67945 0.3048)
			(end -0.67945 -0.305054)
			(stroke
				(width 0.1)
				(type default)
			)
			(layer "F.Fab")
		)
		(fp_line
			(start -0.12065 0.3048)
			(end -0.67945 0.3048)
			(stroke
				(width 0.1)
				(type default)
			)
			(layer "F.Fab")
		)
		(fp_line
			(start 0.120396 0.3048)
			(end 0.120396 0.2794)
			(stroke
				(width 0.1)
				(type default)
			)
			(layer "F.Fab")
		)
		(fp_line
			(start 0.67945 0.3048)
			(end 0.120396 0.3048)
			(stroke
				(width 0.1)
				(type default)
			)
			(layer "F.Fab")
		)
		(fp_line
			(start -0.12065 0.2794)
			(end -0.12065 0.3048)
			(stroke
				(width 0.1)
				(type default)
			)
			(layer "F.Fab")
		)
		(fp_line
			(start 0.120396 0.2794)
			(end -0.12065 0.2794)
			(stroke
				(width 0.1)
				(type default)
			)
			(layer "F.Fab")
		)
		(fp_line
			(start -0.12065 -0.2794)
			(end 0.12065 -0.2794)
			(stroke
				(width 0.1)
				(type default)
			)
			(layer "F.Fab")
		)
		(fp_line
			(start 0.12065 -0.2794)
			(end 0.12065 -0.3048)
			(stroke
				(width 0.1)
				(type default)
			)
			(layer "F.Fab")
		)
		(fp_line
			(start 0.12065 -0.3048)
			(end 0.67945 -0.3048)
			(stroke
				(width 0.1)
				(type default)
			)
			(layer "F.Fab")
		)
		(fp_line
			(start 0.67945 -0.3048)
			(end 0.67945 0.3048)
			(stroke
				(width 0.1)
				(type default)
			)
			(layer "F.Fab")
		)
		(fp_line
			(start -0.67945 -0.305054)
			(end -0.12065 -0.305054)
			(stroke
				(width 0.1)
				(type default)
			)
			(layer "F.Fab")
		)
		(fp_line
			(start -0.12065 -0.305054)
			(end -0.12065 -0.2794)
			(stroke
				(width 0.1)
				(type default)
			)
			(layer "F.Fab")
		)
		(pad "1" smd circle
			(at -0.40005 0 270)
			(size 0 0)
			(layers "F.Cu" "F.Mask" "F.Paste")
			(net "P3V3_AUX")
		)
		(pad "2" smd circle
			(at 0.40005 0 270)
			(size 0 0)
			(layers "F.Cu" "F.Mask" "F.Paste")
			(net "RST_CP2108_CLI_R_N")
		)
	)
	(footprint ""
		(layer "F.Cu")
		(at 328.820018 -15.649956 180)
		(property "Reference" "H106"
			(at -3.981958 -2.599182 0)
			(unlocked yes)
			(layer "B.SilkS")
			(effects
				(font
					(size 0.7874 0.5842)
					(thickness 0.1524)
				)
				(justify left mirror)
			)
		)
		(property "Value" ""
			(at 0 0 180)
			(layer "F.Fab")
			(effects
				(font
					(size 1.27 1.27)
				)
			)
		)
		(duplicate_pad_numbers_are_jumpers no)
		(pad "1" thru_hole rect
			(at 0 0 180)
			(size 4.2164 5.0038)
			(drill 2.0066
				(offset 0.099822 0)
			)
			(layers "*.Cu" "*.Mask")
			(remove_unused_layers no)
			(net "Net_8557")
			(clearance -0.8509)
			(padstack
				(mode front_inner_back)
				(layer "Inner"
					(shape circle)
					(size 4.0132 4.0132)
					(clearance -0.7493)
				)
				(layer "B.Cu"
					(shape circle)
					(size 4.0132 4.0132)
					(clearance -0.7493)
				)
			)
		)
	)
	(footprint ""
		(layer "F.Cu")
		(at 164.747194 -54.3941)
		(property "Reference" "PU33"
			(at -1.707642 3.195574 0)
			(unlocked yes)
			(layer "F.SilkS")
			(effects
				(font
					(size 0.7874 0.5842)
					(thickness 0.1524)
				)
				(justify left)
			)
		)
		(property "Value" ""
			(at 0 0 0)
			(layer "F.Fab")
			(effects
				(font
					(size 1.27 1.27)
				)
			)
		)
		(duplicate_pad_numbers_are_jumpers no)
		(fp_line
			(start -1.943608 -1.549908)
			(end 1.943608 -1.549908)
			(stroke
				(width 0.1524)
				(type default)
			)
			(layer "F.SilkS")
		)
		(fp_line
			(start -1.943608 1.549908)
			(end -1.943608 -1.549908)
			(stroke
				(width 0.1524)
				(type default)
			)
			(layer "F.SilkS")
		)
		(fp_line
			(start 1.943608 -1.549908)
			(end 1.943608 1.549908)
			(stroke
				(width 0.1524)
				(type default)
			)
			(layer "F.SilkS")
		)
		(fp_line
			(start 1.943608 1.549908)
			(end -1.943608 1.549908)
			(stroke
				(width 0.1524)
				(type default)
			)
			(layer "F.SilkS")
		)
		(fp_poly
			(pts
				(xy -2.019808 -1.549908) (xy -1.257808 -1.549908) (xy -1.257808 -1.880108) (xy -2.019808 -1.880108)
			)
			(stroke
				(width 0)
				(type default)
			)
			(fill yes)
			(layer "F.SilkS")
		)
		(fp_line
			(start -1.549908 -1.549908)
			(end 1.549908 -1.549908)
			(stroke
				(width 0.1)
				(type default)
			)
			(layer "F.Fab")
		)
		(fp_line
			(start -1.549908 1.549908)
			(end -1.549908 -1.549908)
			(stroke
				(width 0.1)
				(type default)
			)
			(layer "F.Fab")
		)
		(fp_line
			(start 1.549908 -1.549908)
			(end 1.549908 1.549908)
			(stroke
				(width 0.1)
				(type default)
			)
			(layer "F.Fab")
		)
		(fp_line
			(start 1.549908 1.549908)
			(end -1.549908 1.549908)
			(stroke
				(width 0.1)
				(type default)
			)
			(layer "F.Fab")
		)
		(fp_poly
			(pts
				(xy -2.019808 -1.549908) (xy -1.257808 -1.549908) (xy -1.257808 -1.880108) (xy -2.019808 -1.880108)
			)
			(stroke
				(width 0)
				(type default)
			)
			(fill yes)
			(layer "F.Fab")
		)
		(pad "1" smd rect
			(at -1.500124 -1.249934 270)
			(size 0.2794 0.6096)
			(layers "F.Cu" "F.Mask" "F.Paste")
			(net "P12V_SSD5_R")
		)
		(pad "2" smd rect
			(at -1.500124 -0.750062 270)
			(size 0.2794 0.6096)
			(layers "F.Cu" "F.Mask" "F.Paste")
			(net "P12V_SSD5_R")
		)
		(pad "3" smd rect
			(at -1.500124 -0.249936 270)
			(size 0.2794 0.6096)
			(layers "F.Cu" "F.Mask" "F.Paste")
			(net "P12V_SSD5_R")
		)
		(pad "4" smd rect
			(at -1.500124 0.249936 270)
			(size 0.2794 0.6096)
			(layers "F.Cu" "F.Mask" "F.Paste")
			(net "P12V_SSD5_R")
		)
		(pad "5" smd rect
			(at -1.500124 0.750062 270)
			(size 0.2794 0.6096)
			(layers "F.Cu" "F.Mask" "F.Paste")
			(net "P12V_SSD5_R")
		)
		(pad "6" smd rect
			(at -1.500124 1.249934 270)
			(size 0.2794 0.6096)
			(layers "F.Cu" "F.Mask" "F.Paste")
			(net "GND")
		)
		(pad "7" smd rect
			(at 1.500124 1.249934 270)
			(size 0.2794 0.6096)
			(layers "F.Cu" "F.Mask" "F.Paste")
			(net "P12V_SSD5_SS")
		)
		(pad "8" smd rect
			(at 1.500124 0.750062 270)
			(size 0.2794 0.6096)
			(layers "F.Cu" "F.Mask" "F.Paste")
			(net "PWRGD_P12V_SSD5")
		)
		(pad "9" smd rect
			(at 1.500124 0.249936 270)
			(size 0.2794 0.6096)
			(layers "F.Cu" "F.Mask" "F.Paste")
			(net "P12V_SSD5_OCP")
		)
		(pad "10" smd rect
			(at 1.500124 -0.249936 270)
			(size 0.2794 0.6096)
			(layers "F.Cu" "F.Mask" "F.Paste")
			(net "P5V_AUX")
		)
		(pad "11" smd rect
			(at 1.500124 -0.750062 270)
			(size 0.2794 0.6096)
			(layers "F.Cu" "F.Mask" "F.Paste")
			(net "SSD5_PWR_EN_R")
		)
		(pad "12" smd rect
			(at 1.500124 -1.249934 270)
			(size 0.2794 0.6096)
			(layers "F.Cu" "F.Mask" "F.Paste")
			(net "P12V_AUX")
		)
		(pad "13" smd rect
			(at 0 0)
			(size 1.9812 2.7178)
			(layers "F.Cu" "F.Mask" "F.Paste")
			(net "P12V_AUX")
		)
		(zone
			(layer "F.Cu")
			(hatch none 0.5)
			(connect_pads
				(clearance 0)
			)
			(min_thickness 0.25)
			(keepout
				(tracks not_allowed)
				(vias allowed)
				(pads allowed)
				(copperpour not_allowed)
				(footprints allowed)
			)
			(placement
				(enabled no)
				(sheetname "")
			)
			(fill
				(thermal_gap 0.5)
				(thermal_bridge_width 0.5)
				(island_removal_mode 0)
			)
			(polygon
				(pts
					(xy 165.890194 -55.9435) (xy 165.890194 -55.8165) (xy 165.890194 -52.8447) (xy 165.890194 -52.844192)
					(xy 163.604194 -52.844192) (xy 163.604194 -52.8447) (xy 163.604194 -52.9717) (xy 163.604194 -54.3941)
					(xy 163.705794 -54.3941) (xy 163.705794 -52.9717) (xy 165.788594 -52.9717) (xy 165.788594 -55.8165)
					(xy 163.705794 -55.8165) (xy 163.705794 -54.4195) (xy 163.604194 -54.4195) (xy 163.604194 -55.8165)
					(xy 163.604194 -55.9435) (xy 163.604194 -55.944008) (xy 165.890194 -55.944008)
				)
			)
		)
	)
)
